FILE_TYPE=LIBRARY_PARTS;
primitive 'DT1240E04LP7';
  pin
    'IO1':
      PIN_NUMBER='(1)';
      BIDIRECTIONAL='TRUE';
      INPUT_LOAD='(-0.01,0.01)';
      OUTPUT_LOAD='(1.0,-1.0)';
    'VSS1':
      PIN_NUMBER='(3)';
      PINUSE='POWER';
      NO_LOAD_CHECK='Both';
      NO_IO_CHECK='Both';
      NO_ASSERT_CHECK='TRUE';
      NO_DIR_CHECK='TRUE';
      ALLOW_CONNECT='TRUE';
    'IO3':
      PIN_NUMBER='(4)';
      BIDIRECTIONAL='TRUE';
      INPUT_LOAD='(-0.01,0.01)';
      OUTPUT_LOAD='(1.0,-1.0)';
    'NC1':
      PIN_NUMBER='(6)';
      OUTPUT_TYPE='(TS,TS)';
      INPUT_LOAD='(-0.01,0.01)';
      OUTPUT_LOAD='(1.0,-1.0)';
    'VSS2':
      PIN_NUMBER='(8)';
      PINUSE='POWER';
      NO_LOAD_CHECK='Both';
      NO_IO_CHECK='Both';
      NO_ASSERT_CHECK='TRUE';
      NO_DIR_CHECK='TRUE';
      ALLOW_CONNECT='TRUE';
    'NC3':
      PIN_NUMBER='(9)';
      OUTPUT_TYPE='(TS,TS)';
      INPUT_LOAD='(-0.01,0.01)';
      OUTPUT_LOAD='(1.0,-1.0)';
    'NC4':
      PIN_NUMBER='(10)';
      OUTPUT_TYPE='(TS,TS)';
      INPUT_LOAD='(-0.01,0.01)';
      OUTPUT_LOAD='(1.0,-1.0)';
    'IO2':
      PIN_NUMBER='(2)';
      BIDIRECTIONAL='TRUE';
      INPUT_LOAD='(-0.01,0.01)';
      OUTPUT_LOAD='(1.0,-1.0)';
    'IO4':
      PIN_NUMBER='(5)';
      BIDIRECTIONAL='TRUE';
      INPUT_LOAD='(-0.01,0.01)';
      OUTPUT_LOAD='(1.0,-1.0)';
    'NC2':
      PIN_NUMBER='(7)';
      OUTPUT_TYPE='(TS,TS)';
      INPUT_LOAD='(-0.01,0.01)';
      OUTPUT_LOAD='(1.0,-1.0)';
  end_pin;
  body
    PART_NAME='DT1240E04LP7';
    BODY_NAME='DT1240E04LP7';
    PHYS_DES_PREFIX='D';
    CLASS='DISCRETE';
  end_body;
end_primitive;

END.
